(kicad_pcb
	(version 20260206)
	(generator "pcbnew")
	(generator_version "10.0")
	(general
		(thickness 1.6)
		(legacy_teardrops no)
	)
	(paper "A4")
	(title_block
		(title "12092022_DA0F0TMDCD0_F0T_Management_Board_D_brd_V3_OCP.brd")
		(comment 1 "Grand Teton / footprints 986-991 of 1440")
	)
	(layers
		(0 "F.Cu" signal "TOP")
		(4 "In1.Cu" signal "GND")
		(6 "In2.Cu" signal "IN1")
		(8 "In3.Cu" signal "GND1")
		(10 "In4.Cu" signal "IN2")
		(12 "In5.Cu" signal "VCC")
		(14 "In6.Cu" signal "VCC1")
		(16 "In7.Cu" signal "IN3")
		(18 "In8.Cu" signal "GND2")
		(20 "In9.Cu" signal "IN4")
		(22 "In10.Cu" signal "GND3")
		(2 "B.Cu" signal "BOTTOM")
		(9 "F.Adhes" user "F.Adhesive")
		(11 "B.Adhes" user "B.Adhesive")
		(13 "F.Paste" user "Package Geometry/Pastemask Top")
		(15 "B.Paste" user "Package Geometry/Pastemask Bottom")
		(5 "F.SilkS" user "Ref Des/Silkscreen Top")
		(7 "B.SilkS" user "Ref Des/Silkscreen Bottom")
		(1 "F.Mask" user "Board Geometry/Soldermask Top")
		(3 "B.Mask" user "Board Geometry/Soldermask Bottom")
		(17 "Dwgs.User" user "User.Drawings")
		(19 "Cmts.User" user "User.Comments")
		(21 "Eco1.User" user "User.Eco1")
		(23 "Eco2.User" user "User.Eco2")
		(25 "Edge.Cuts" user "Board Geometry/Outline")
		(27 "Margin" user)
		(31 "F.CrtYd" user "Package Geometry/Place Bound Top")
		(29 "B.CrtYd" user "Package Geometry/Place Bound Bottom")
		(35 "F.Fab" user "Ref Des/Assembly Top")
		(33 "B.Fab" user "Ref Des/Assembly Bottom")
	)
	(footprint ""
		(layer "B.Cu")
		(at 56.7436 -67.818 -90)
		(property "Reference" "R402"
			(at 0 0 90)
			(layer "B.SilkS")
			(hide yes)
			(effects
				(font
					(size 1.27 1.27)
				)
				(justify mirror)
			)
		)
		(property "Value" ""
			(at 0 0 90)
			(layer "B.Fab")
			(effects
				(font
					(size 1.27 1.27)
				)
				(justify mirror)
			)
		)
		(duplicate_pad_numbers_are_jumpers no)
		(fp_line
			(start -0.7874 0.4064)
			(end 0.7874 0.4064)
			(stroke
				(width 0.1524)
				(type default)
			)
			(layer "B.SilkS")
		)
		(fp_line
			(start 0.7874 0.4064)
			(end 0.7874 -0.4064)
			(stroke
				(width 0.1524)
				(type default)
			)
			(layer "B.SilkS")
		)
		(fp_line
			(start -0.7874 -0.4064)
			(end -0.7874 0.4064)
			(stroke
				(width 0.1524)
				(type default)
			)
			(layer "B.SilkS")
		)
		(fp_line
			(start 0.7874 -0.4064)
			(end -0.7874 -0.4064)
			(stroke
				(width 0.1524)
				(type default)
			)
			(layer "B.SilkS")
		)
		(fp_line
			(start -0.67945 0.3048)
			(end -0.120396 0.3048)
			(stroke
				(width 0.1)
				(type default)
			)
			(layer "B.Fab")
		)
		(fp_line
			(start -0.120396 0.3048)
			(end -0.120396 0.2794)
			(stroke
				(width 0.1)
				(type default)
			)
			(layer "B.Fab")
		)
		(fp_line
			(start 0.12065 0.3048)
			(end 0.67945 0.3048)
			(stroke
				(width 0.1)
				(type default)
			)
			(layer "B.Fab")
		)
		(fp_line
			(start 0.67945 0.3048)
			(end 0.67945 -0.305054)
			(stroke
				(width 0.1)
				(type default)
			)
			(layer "B.Fab")
		)
		(fp_line
			(start -0.120396 0.2794)
			(end 0.12065 0.2794)
			(stroke
				(width 0.1)
				(type default)
			)
			(layer "B.Fab")
		)
		(fp_line
			(start 0.12065 0.2794)
			(end 0.12065 0.3048)
			(stroke
				(width 0.1)
				(type default)
			)
			(layer "B.Fab")
		)
		(fp_line
			(start -0.12065 -0.2794)
			(end -0.12065 -0.3048)
			(stroke
				(width 0.1)
				(type default)
			)
			(layer "B.Fab")
		)
		(fp_line
			(start 0.12065 -0.2794)
			(end -0.12065 -0.2794)
			(stroke
				(width 0.1)
				(type default)
			)
			(layer "B.Fab")
		)
		(fp_line
			(start -0.67945 -0.3048)
			(end -0.67945 0.3048)
			(stroke
				(width 0.1)
				(type default)
			)
			(layer "B.Fab")
		)
		(fp_line
			(start -0.12065 -0.3048)
			(end -0.67945 -0.3048)
			(stroke
				(width 0.1)
				(type default)
			)
			(layer "B.Fab")
		)
		(fp_line
			(start 0.12065 -0.305054)
			(end 0.12065 -0.2794)
			(stroke
				(width 0.1)
				(type default)
			)
			(layer "B.Fab")
		)
		(fp_line
			(start 0.67945 -0.305054)
			(end 0.12065 -0.305054)
			(stroke
				(width 0.1)
				(type default)
			)
			(layer "B.Fab")
		)
		(pad "1" smd circle
			(at 0.40005 0 90)
			(size 0 0)
			(layers "B.Cu" "B.Mask" "B.Paste")
			(net "PU_FWSPIWP_N")
		)
		(pad "2" smd circle
			(at -0.40005 0 90)
			(size 0 0)
			(layers "B.Cu" "B.Mask" "B.Paste")
			(net "PU_FWSPIWP_N_R")
		)
	)
	(footprint ""
		(layer "B.Cu")
		(at 39.742618 -52.779676 -90)
		(property "Reference" "R279"
			(at 0 0 90)
			(layer "B.SilkS")
			(hide yes)
			(effects
				(font
					(size 1.27 1.27)
				)
				(justify mirror)
			)
		)
		(property "Value" ""
			(at 0 0 90)
			(layer "B.Fab")
			(effects
				(font
					(size 1.27 1.27)
				)
				(justify mirror)
			)
		)
		(duplicate_pad_numbers_are_jumpers no)
		(fp_line
			(start -0.7874 0.4064)
			(end 0.7874 0.4064)
			(stroke
				(width 0.1524)
				(type default)
			)
			(layer "B.SilkS")
		)
		(fp_line
			(start 0.7874 0.4064)
			(end 0.7874 -0.4064)
			(stroke
				(width 0.1524)
				(type default)
			)
			(layer "B.SilkS")
		)
		(fp_line
			(start -0.7874 -0.4064)
			(end -0.7874 0.4064)
			(stroke
				(width 0.1524)
				(type default)
			)
			(layer "B.SilkS")
		)
		(fp_line
			(start 0.7874 -0.4064)
			(end -0.7874 -0.4064)
			(stroke
				(width 0.1524)
				(type default)
			)
			(layer "B.SilkS")
		)
		(fp_line
			(start -0.67945 0.3048)
			(end -0.120396 0.3048)
			(stroke
				(width 0.1)
				(type default)
			)
			(layer "B.Fab")
		)
		(fp_line
			(start -0.120396 0.3048)
			(end -0.120396 0.2794)
			(stroke
				(width 0.1)
				(type default)
			)
			(layer "B.Fab")
		)
		(fp_line
			(start 0.12065 0.3048)
			(end 0.67945 0.3048)
			(stroke
				(width 0.1)
				(type default)
			)
			(layer "B.Fab")
		)
		(fp_line
			(start 0.67945 0.3048)
			(end 0.67945 -0.305054)
			(stroke
				(width 0.1)
				(type default)
			)
			(layer "B.Fab")
		)
		(fp_line
			(start -0.120396 0.2794)
			(end 0.12065 0.2794)
			(stroke
				(width 0.1)
				(type default)
			)
			(layer "B.Fab")
		)
		(fp_line
			(start 0.12065 0.2794)
			(end 0.12065 0.3048)
			(stroke
				(width 0.1)
				(type default)
			)
			(layer "B.Fab")
		)
		(fp_line
			(start -0.12065 -0.2794)
			(end -0.12065 -0.3048)
			(stroke
				(width 0.1)
				(type default)
			)
			(layer "B.Fab")
		)
		(fp_line
			(start 0.12065 -0.2794)
			(end -0.12065 -0.2794)
			(stroke
				(width 0.1)
				(type default)
			)
			(layer "B.Fab")
		)
		(fp_line
			(start -0.67945 -0.3048)
			(end -0.67945 0.3048)
			(stroke
				(width 0.1)
				(type default)
			)
			(layer "B.Fab")
		)
		(fp_line
			(start -0.12065 -0.3048)
			(end -0.67945 -0.3048)
			(stroke
				(width 0.1)
				(type default)
			)
			(layer "B.Fab")
		)
		(fp_line
			(start 0.12065 -0.305054)
			(end 0.12065 -0.2794)
			(stroke
				(width 0.1)
				(type default)
			)
			(layer "B.Fab")
		)
		(fp_line
			(start 0.67945 -0.305054)
			(end 0.12065 -0.305054)
			(stroke
				(width 0.1)
				(type default)
			)
			(layer "B.Fab")
		)
		(pad "1" smd circle
			(at 0.40005 0 90)
			(size 0 0)
			(layers "B.Cu" "B.Mask" "B.Paste")
			(net "P1V0_AUX")
		)
		(pad "2" smd circle
			(at -0.40005 0 90)
			(size 0 0)
			(layers "B.Cu" "B.Mask" "B.Paste")
			(net "P1V2_P1V0_I3C_VDDL1")
		)
	)
	(footprint ""
		(layer "B.Cu")
		(at 62.992 -24.257 -90)
		(property "Reference" "C149"
			(at 0 0 90)
			(layer "B.SilkS")
			(hide yes)
			(effects
				(font
					(size 1.27 1.27)
				)
				(justify mirror)
			)
		)
		(property "Value" ""
			(at 0 0 90)
			(layer "B.Fab")
			(effects
				(font
					(size 1.27 1.27)
				)
				(justify mirror)
			)
		)
		(duplicate_pad_numbers_are_jumpers no)
		(fp_line
			(start -0.7874 0.4064)
			(end 0.7874 0.4064)
			(stroke
				(width 0.1524)
				(type default)
			)
			(layer "B.SilkS")
		)
		(fp_line
			(start 0.7874 0.4064)
			(end 0.7874 -0.4064)
			(stroke
				(width 0.1524)
				(type default)
			)
			(layer "B.SilkS")
		)
		(fp_line
			(start -0.7874 -0.4064)
			(end -0.7874 0.4064)
			(stroke
				(width 0.1524)
				(type default)
			)
			(layer "B.SilkS")
		)
		(fp_line
			(start 0.7874 -0.4064)
			(end -0.7874 -0.4064)
			(stroke
				(width 0.1524)
				(type default)
			)
			(layer "B.SilkS")
		)
		(fp_line
			(start -0.67945 0.3048)
			(end -0.120396 0.3048)
			(stroke
				(width 0.1)
				(type default)
			)
			(layer "B.Fab")
		)
		(fp_line
			(start -0.120396 0.3048)
			(end -0.120396 0.2794)
			(stroke
				(width 0.1)
				(type default)
			)
			(layer "B.Fab")
		)
		(fp_line
			(start 0.12065 0.3048)
			(end 0.67945 0.3048)
			(stroke
				(width 0.1)
				(type default)
			)
			(layer "B.Fab")
		)
		(fp_line
			(start 0.67945 0.3048)
			(end 0.67945 -0.305054)
			(stroke
				(width 0.1)
				(type default)
			)
			(layer "B.Fab")
		)
		(fp_line
			(start -0.120396 0.2794)
			(end 0.12065 0.2794)
			(stroke
				(width 0.1)
				(type default)
			)
			(layer "B.Fab")
		)
		(fp_line
			(start 0.12065 0.2794)
			(end 0.12065 0.3048)
			(stroke
				(width 0.1)
				(type default)
			)
			(layer "B.Fab")
		)
		(fp_line
			(start -0.12065 -0.2794)
			(end -0.12065 -0.3048)
			(stroke
				(width 0.1)
				(type default)
			)
			(layer "B.Fab")
		)
		(fp_line
			(start 0.12065 -0.2794)
			(end -0.12065 -0.2794)
			(stroke
				(width 0.1)
				(type default)
			)
			(layer "B.Fab")
		)
		(fp_line
			(start -0.67945 -0.3048)
			(end -0.67945 0.3048)
			(stroke
				(width 0.1)
				(type default)
			)
			(layer "B.Fab")
		)
		(fp_line
			(start -0.12065 -0.3048)
			(end -0.67945 -0.3048)
			(stroke
				(width 0.1)
				(type default)
			)
			(layer "B.Fab")
		)
		(fp_line
			(start 0.12065 -0.305054)
			(end 0.12065 -0.2794)
			(stroke
				(width 0.1)
				(type default)
			)
			(layer "B.Fab")
		)
		(fp_line
			(start 0.67945 -0.305054)
			(end 0.12065 -0.305054)
			(stroke
				(width 0.1)
				(type default)
			)
			(layer "B.Fab")
		)
		(pad "1" smd circle
			(at 0.40005 0 90)
			(size 0 0)
			(layers "B.Cu" "B.Mask" "B.Paste")
			(net "P3V3_AUX")
		)
		(pad "2" smd circle
			(at -0.40005 0 90)
			(size 0 0)
			(layers "B.Cu" "B.Mask" "B.Paste")
			(net "GND")
		)
	)
	(footprint ""
		(layer "B.Cu")
		(at 43.942 -19.431 90)
		(property "Reference" "R693"
			(at 0 0 90)
			(layer "B.SilkS")
			(hide yes)
			(effects
				(font
					(size 1.27 1.27)
				)
				(justify mirror)
			)
		)
		(property "Value" ""
			(at 0 0 90)
			(layer "B.Fab")
			(effects
				(font
					(size 1.27 1.27)
				)
				(justify mirror)
			)
		)
		(duplicate_pad_numbers_are_jumpers no)
		(fp_line
			(start 0.7874 -0.4064)
			(end -0.7874 -0.4064)
			(stroke
				(width 0.1524)
				(type default)
			)
			(layer "B.SilkS")
		)
		(fp_line
			(start -0.7874 -0.4064)
			(end -0.7874 0.4064)
			(stroke
				(width 0.1524)
				(type default)
			)
			(layer "B.SilkS")
		)
		(fp_line
			(start 0.7874 0.4064)
			(end 0.7874 -0.4064)
			(stroke
				(width 0.1524)
				(type default)
			)
			(layer "B.SilkS")
		)
		(fp_line
			(start -0.7874 0.4064)
			(end 0.7874 0.4064)
			(stroke
				(width 0.1524)
				(type default)
			)
			(layer "B.SilkS")
		)
		(fp_line
			(start 0.67945 -0.305054)
			(end 0.12065 -0.305054)
			(stroke
				(width 0.1)
				(type default)
			)
			(layer "B.Fab")
		)
		(fp_line
			(start 0.12065 -0.305054)
			(end 0.12065 -0.2794)
			(stroke
				(width 0.1)
				(type default)
			)
			(layer "B.Fab")
		)
		(fp_line
			(start -0.12065 -0.3048)
			(end -0.67945 -0.3048)
			(stroke
				(width 0.1)
				(type default)
			)
			(layer "B.Fab")
		)
		(fp_line
			(start -0.67945 -0.3048)
			(end -0.67945 0.3048)
			(stroke
				(width 0.1)
				(type default)
			)
			(layer "B.Fab")
		)
		(fp_line
			(start 0.12065 -0.2794)
			(end -0.12065 -0.2794)
			(stroke
				(width 0.1)
				(type default)
			)
			(layer "B.Fab")
		)
		(fp_line
			(start -0.12065 -0.2794)
			(end -0.12065 -0.3048)
			(stroke
				(width 0.1)
				(type default)
			)
			(layer "B.Fab")
		)
		(fp_line
			(start 0.12065 0.2794)
			(end 0.12065 0.3048)
			(stroke
				(width 0.1)
				(type default)
			)
			(layer "B.Fab")
		)
		(fp_line
			(start -0.120396 0.2794)
			(end 0.12065 0.2794)
			(stroke
				(width 0.1)
				(type default)
			)
			(layer "B.Fab")
		)
		(fp_line
			(start 0.67945 0.3048)
			(end 0.67945 -0.305054)
			(stroke
				(width 0.1)
				(type default)
			)
			(layer "B.Fab")
		)
		(fp_line
			(start 0.12065 0.3048)
			(end 0.67945 0.3048)
			(stroke
				(width 0.1)
				(type default)
			)
			(layer "B.Fab")
		)
		(fp_line
			(start -0.120396 0.3048)
			(end -0.120396 0.2794)
			(stroke
				(width 0.1)
				(type default)
			)
			(layer "B.Fab")
		)
		(fp_line
			(start -0.67945 0.3048)
			(end -0.120396 0.3048)
			(stroke
				(width 0.1)
				(type default)
			)
			(layer "B.Fab")
		)
		(pad "1" smd circle
			(at 0.40005 0 270)
			(size 0 0)
			(layers "B.Cu" "B.Mask" "B.Paste")
			(net "DEBUG_PORT_PRSNT")
		)
		(pad "2" smd circle
			(at -0.40005 0 270)
			(size 0 0)
			(layers "B.Cu" "B.Mask" "B.Paste")
			(net "DEBUG_PORT_PRSNT_R")
		)
	)
	(footprint ""
		(layer "B.Cu")
		(at 41.966134 -48.44415)
		(property "Reference" "R819"
			(at 0 0 0)
			(layer "B.SilkS")
			(hide yes)
			(effects
				(font
					(size 1.27 1.27)
				)
				(justify mirror)
			)
		)
		(property "Value" ""
			(at 0 0 0)
			(layer "B.Fab")
			(effects
				(font
					(size 1.27 1.27)
				)
				(justify mirror)
			)
		)
		(duplicate_pad_numbers_are_jumpers no)
		(fp_line
			(start -0.7874 -0.4064)
			(end -0.7874 0.4064)
			(stroke
				(width 0.1524)
				(type default)
			)
			(layer "B.SilkS")
		)
		(fp_line
			(start -0.7874 0.4064)
			(end 0.7874 0.4064)
			(stroke
				(width 0.1524)
				(type default)
			)
			(layer "B.SilkS")
		)
		(fp_line
			(start 0.7874 -0.4064)
			(end -0.7874 -0.4064)
			(stroke
				(width 0.1524)
				(type default)
			)
			(layer "B.SilkS")
		)
		(fp_line
			(start 0.7874 0.4064)
			(end 0.7874 -0.4064)
			(stroke
				(width 0.1524)
				(type default)
			)
			(layer "B.SilkS")
		)
		(fp_line
			(start -0.67945 -0.3048)
			(end -0.67945 0.3048)
			(stroke
				(width 0.1)
				(type default)
			)
			(layer "B.Fab")
		)
		(fp_line
			(start -0.67945 0.3048)
			(end -0.120396 0.3048)
			(stroke
				(width 0.1)
				(type default)
			)
			(layer "B.Fab")
		)
		(fp_line
			(start -0.12065 -0.3048)
			(end -0.67945 -0.3048)
			(stroke
				(width 0.1)
				(type default)
			)
			(layer "B.Fab")
		)
		(fp_line
			(start -0.12065 -0.2794)
			(end -0.12065 -0.3048)
			(stroke
				(width 0.1)
				(type default)
			)
			(layer "B.Fab")
		)
		(fp_line
			(start -0.120396 0.2794)
			(end 0.12065 0.2794)
			(stroke
				(width 0.1)
				(type default)
			)
			(layer "B.Fab")
		)
		(fp_line
			(start -0.120396 0.3048)
			(end -0.120396 0.2794)
			(stroke
				(width 0.1)
				(type default)
			)
			(layer "B.Fab")
		)
		(fp_line
			(start 0.12065 -0.305054)
			(end 0.12065 -0.2794)
			(stroke
				(width 0.1)
				(type default)
			)
			(layer "B.Fab")
		)
		(fp_line
			(start 0.12065 -0.2794)
			(end -0.12065 -0.2794)
			(stroke
				(width 0.1)
				(type default)
			)
			(layer "B.Fab")
		)
		(fp_line
			(start 0.12065 0.2794)
			(end 0.12065 0.3048)
			(stroke
				(width 0.1)
				(type default)
			)
			(layer "B.Fab")
		)
		(fp_line
			(start 0.12065 0.3048)
			(end 0.67945 0.3048)
			(stroke
				(width 0.1)
				(type default)
			)
			(layer "B.Fab")
		)
		(fp_line
			(start 0.67945 -0.305054)
			(end 0.12065 -0.305054)
			(stroke
				(width 0.1)
				(type default)
			)
			(layer "B.Fab")
		)
		(fp_line
			(start 0.67945 0.3048)
			(end 0.67945 -0.305054)
			(stroke
				(width 0.1)
				(type default)
			)
			(layer "B.Fab")
		)
		(pad "1" smd circle
			(at 0.40005 0 180)
			(size 0 0)
			(layers "B.Cu" "B.Mask" "B.Paste")
			(net "SMB_BMC_MM14_R_SCL")
		)
		(pad "2" smd circle
			(at -0.40005 0 180)
			(size 0 0)
			(layers "B.Cu" "B.Mask" "B.Paste")
			(net "GND")
		)
	)
	(footprint ""
		(layer "B.Cu")
		(at 43.88866 -76.4286 180)
		(property "Reference" "R852"
			(at 0 0 0)
			(layer "B.SilkS")
			(hide yes)
			(effects
				(font
					(size 1.27 1.27)
				)
				(justify mirror)
			)
		)
		(property "Value" ""
			(at 0 0 0)
			(layer "B.Fab")
			(effects
				(font
					(size 1.27 1.27)
				)
				(justify mirror)
			)
		)
		(duplicate_pad_numbers_are_jumpers no)
		(fp_line
			(start 0.7874 0.4064)
			(end 0.7874 -0.4064)
			(stroke
				(width 0.1524)
				(type default)
			)
			(layer "B.SilkS")
		)
		(fp_line
			(start 0.7874 -0.4064)
			(end -0.7874 -0.4064)
			(stroke
				(width 0.1524)
				(type default)
			)
			(layer "B.SilkS")
		)
		(fp_line
			(start -0.7874 0.4064)
			(end 0.7874 0.4064)
			(stroke
				(width 0.1524)
				(type default)
			)
			(layer "B.SilkS")
		)
		(fp_line
			(start -0.7874 -0.4064)
			(end -0.7874 0.4064)
			(stroke
				(width 0.1524)
				(type default)
			)
			(layer "B.SilkS")
		)
		(fp_line
			(start 0.67945 0.3048)
			(end 0.67945 -0.305054)
			(stroke
				(width 0.1)
				(type default)
			)
			(layer "B.Fab")
		)
		(fp_line
			(start 0.67945 -0.305054)
			(end 0.12065 -0.305054)
			(stroke
				(width 0.1)
				(type default)
			)
			(layer "B.Fab")
		)
		(fp_line
			(start 0.12065 0.3048)
			(end 0.67945 0.3048)
			(stroke
				(width 0.1)
				(type default)
			)
			(layer "B.Fab")
		)
		(fp_line
			(start 0.12065 0.2794)
			(end 0.12065 0.3048)
			(stroke
				(width 0.1)
				(type default)
			)
			(layer "B.Fab")
		)
		(fp_line
			(start 0.12065 -0.2794)
			(end -0.12065 -0.2794)
			(stroke
				(width 0.1)
				(type default)
			)
			(layer "B.Fab")
		)
		(fp_line
			(start 0.12065 -0.305054)
			(end 0.12065 -0.2794)
			(stroke
				(width 0.1)
				(type default)
			)
			(layer "B.Fab")
		)
		(fp_line
			(start -0.120396 0.3048)
			(end -0.120396 0.2794)
			(stroke
				(width 0.1)
				(type default)
			)
			(layer "B.Fab")
		)
		(fp_line
			(start -0.120396 0.2794)
			(end 0.12065 0.2794)
			(stroke
				(width 0.1)
				(type default)
			)
			(layer "B.Fab")
		)
		(fp_line
			(start -0.12065 -0.2794)
			(end -0.12065 -0.3048)
			(stroke
				(width 0.1)
				(type default)
			)
			(layer "B.Fab")
		)
		(fp_line
			(start -0.12065 -0.3048)
			(end -0.67945 -0.3048)
			(stroke
				(width 0.1)
				(type default)
			)
			(layer "B.Fab")
		)
		(fp_line
			(start -0.67945 0.3048)
			(end -0.120396 0.3048)
			(stroke
				(width 0.1)
				(type default)
			)
			(layer "B.Fab")
		)
		(fp_line
			(start -0.67945 -0.3048)
			(end -0.67945 0.3048)
			(stroke
				(width 0.1)
				(type default)
			)
			(layer "B.Fab")
		)
		(pad "1" smd circle
			(at 0.40005 0)
			(size 0 0)
			(layers "B.Cu" "B.Mask" "B.Paste")
			(net "FM_BMC_MUX_CS_SPI_SEL_0")
		)
		(pad "2" smd circle
			(at -0.40005 0)
			(size 0 0)
			(layers "B.Cu" "B.Mask" "B.Paste")
			(net "FM_BMC_BIOS_MUX_CS_SPI_R_SEL_0")
		)
	)
)
